# T6G (Grand Teton) — schematic netlist excerpt (pin names and nets, part order shuffled) for the footprints in the layout excerpt that follows; sources: Cadence DE-HDL packaged netlist, KiCad conversion of 04192023_DAF0TMB3IC0_F0TG_MB_C_brd_V02_OCP.brd

C2457  Q_CAP  22UF 4V 20% X6S  pkg C0402  page 74 : A = PVDDCR_SOC_P1 ; B = GND
R421  Q_RES  1K 1% EMPTY  pkg 0402LF  page 28 : A = PVDD11_S3_P0 ; B = I3C_1_SPD_DDRGL_CPU0_R_SCL

(kicad_pcb
	(version 20260206)
	(generator "pcbnew")
	(generator_version "10.0")
	(general
		(thickness 1.6)
		(legacy_teardrops no)
	)
	(paper "A4")
	(title_block
		(title "04192023_DAF0TMB3IC0_F0TG_MB_C_brd_V02_OCP.brd")
		(comment 1 "Grand Teton / footprints 7014-7015 of 8354")
	)
	(layers
		(0 "F.Cu" signal "TOP")
		(4 "In1.Cu" signal "GND")
		(6 "In2.Cu" signal "IN1")
		(8 "In3.Cu" signal "GND1")
		(10 "In4.Cu" signal "IN2")
		(12 "In5.Cu" signal "GND2")
		(14 "In6.Cu" signal "IN3")
		(16 "In7.Cu" signal "GND3")
		(18 "In8.Cu" signal "VCC")
		(20 "In9.Cu" signal "VCC1")
		(22 "In10.Cu" signal "GND4")
		(24 "In11.Cu" signal "IN4")
		(26 "In12.Cu" signal "GND5")
		(28 "In13.Cu" signal "IN5")
		(30 "In14.Cu" signal "GND6")
		(32 "In15.Cu" signal "IN6")
		(34 "In16.Cu" signal "GND7")
		(2 "B.Cu" signal "BOTTOM")
		(9 "F.Adhes" user "F.Adhesive")
		(11 "B.Adhes" user "B.Adhesive")
		(13 "F.Paste" user "Package Geometry/Pastemask Top")
		(15 "B.Paste" user "Package Geometry/Pastemask Bottom")
		(5 "F.SilkS" user "Ref Des/Silkscreen Top")
		(7 "B.SilkS" user "Ref Des/Silkscreen Bottom")
		(1 "F.Mask" user "Board Geometry/Soldermask Top")
		(3 "B.Mask" user "Board Geometry/Soldermask Bottom")
		(17 "Dwgs.User" user "User.Drawings")
		(19 "Cmts.User" user "User.Comments")
		(21 "Eco1.User" user "User.Eco1")
		(23 "Eco2.User" user "User.Eco2")
		(25 "Edge.Cuts" user "Board Geometry/Outline")
		(27 "Margin" user)
		(31 "F.CrtYd" user "Package Geometry/Place Bound Top")
		(29 "B.CrtYd" user "Package Geometry/Place Bound Bottom")
		(35 "F.Fab" user "Ref Des/Assembly Top")
		(33 "B.Fab" user "Ref Des/Assembly Bottom")
	)
	(footprint ""
		(layer "B.Cu")
		(at 379.266958 -205.101952 -90)
		(property "Reference" "R421"
			(at 0 0 90)
			(layer "B.SilkS")
			(hide yes)
			(effects
				(font
					(size 1.27 1.27)
				)
				(justify mirror)
			)
		)
		(property "Value" ""
			(at 0 0 90)
			(layer "B.Fab")
			(effects
				(font
					(size 1.27 1.27)
				)
				(justify mirror)
			)
		)
		(duplicate_pad_numbers_are_jumpers no)
		(fp_line
			(start -0.7874 0.4064)
			(end 0.7874 0.4064)
			(stroke
				(width 0.1524)
				(type default)
			)
			(layer "B.SilkS")
		)
		(fp_line
			(start 0.7874 0.4064)
			(end 0.7874 -0.4064)
			(stroke
				(width 0.1524)
				(type default)
			)
			(layer "B.SilkS")
		)
		(fp_line
			(start -0.7874 -0.4064)
			(end -0.7874 0.4064)
			(stroke
				(width 0.1524)
				(type default)
			)
			(layer "B.SilkS")
		)
		(fp_line
			(start 0.7874 -0.4064)
			(end -0.7874 -0.4064)
			(stroke
				(width 0.1524)
				(type default)
			)
			(layer "B.SilkS")
		)
		(fp_line
			(start -0.67945 0.3048)
			(end -0.120396 0.3048)
			(stroke
				(width 0.1)
				(type default)
			)
			(layer "B.Fab")
		)
		(fp_line
			(start -0.120396 0.3048)
			(end -0.120396 0.2794)
			(stroke
				(width 0.1)
				(type default)
			)
			(layer "B.Fab")
		)
		(fp_line
			(start 0.12065 0.3048)
			(end 0.67945 0.3048)
			(stroke
				(width 0.1)
				(type default)
			)
			(layer "B.Fab")
		)
		(fp_line
			(start 0.67945 0.3048)
			(end 0.67945 -0.305054)
			(stroke
				(width 0.1)
				(type default)
			)
			(layer "B.Fab")
		)
		(fp_line
			(start -0.120396 0.2794)
			(end 0.12065 0.2794)
			(stroke
				(width 0.1)
				(type default)
			)
			(layer "B.Fab")
		)
		(fp_line
			(start 0.12065 0.2794)
			(end 0.12065 0.3048)
			(stroke
				(width 0.1)
				(type default)
			)
			(layer "B.Fab")
		)
		(fp_line
			(start -0.12065 -0.2794)
			(end -0.12065 -0.3048)
			(stroke
				(width 0.1)
				(type default)
			)
			(layer "B.Fab")
		)
		(fp_line
			(start 0.12065 -0.2794)
			(end -0.12065 -0.2794)
			(stroke
				(width 0.1)
				(type default)
			)
			(layer "B.Fab")
		)
		(fp_line
			(start -0.67945 -0.3048)
			(end -0.67945 0.3048)
			(stroke
				(width 0.1)
				(type default)
			)
			(layer "B.Fab")
		)
		(fp_line
			(start -0.12065 -0.3048)
			(end -0.67945 -0.3048)
			(stroke
				(width 0.1)
				(type default)
			)
			(layer "B.Fab")
		)
		(fp_line
			(start 0.12065 -0.305054)
			(end 0.12065 -0.2794)
			(stroke
				(width 0.1)
				(type default)
			)
			(layer "B.Fab")
		)
		(fp_line
			(start 0.67945 -0.305054)
			(end 0.12065 -0.305054)
			(stroke
				(width 0.1)
				(type default)
			)
			(layer "B.Fab")
		)
		(pad "1" smd circle
			(at 0.40005 0 90)
			(size 0 0)
			(layers "B.Cu" "B.Mask" "B.Paste")
			(net "PVDD11_S3_P0")
		)
		(pad "2" smd circle
			(at -0.40005 0 90)
			(size 0 0)
			(layers "B.Cu" "B.Mask" "B.Paste")
			(net "I3C_1_SPD_DDRGL_CPU0_R_SCL")
		)
	)
	(footprint ""
		(layer "B.Cu")
		(at 121.706386 -255.845564)
		(property "Reference" "C2457"
			(at 0 0 0)
			(layer "B.SilkS")
			(hide yes)
			(effects
				(font
					(size 1.27 1.27)
				)
				(justify mirror)
			)
		)
		(property "Value" ""
			(at 0 0 0)
			(layer "B.Fab")
			(effects
				(font
					(size 1.27 1.27)
				)
				(justify mirror)
			)
		)
		(duplicate_pad_numbers_are_jumpers no)
		(fp_line
			(start -0.7874 -0.4064)
			(end -0.7874 0.4064)
			(stroke
				(width 0.1524)
				(type default)
			)
			(layer "B.SilkS")
		)
		(fp_line
			(start -0.7874 0.4064)
			(end 0.7874 0.4064)
			(stroke
				(width 0.1524)
				(type default)
			)
			(layer "B.SilkS")
		)
		(fp_line
			(start 0.7874 -0.4064)
			(end -0.7874 -0.4064)
			(stroke
				(width 0.1524)
				(type default)
			)
			(layer "B.SilkS")
		)
		(fp_line
			(start 0.7874 0.4064)
			(end 0.7874 -0.4064)
			(stroke
				(width 0.1524)
				(type default)
			)
			(layer "B.SilkS")
		)
		(fp_line
			(start -0.67945 -0.3048)
			(end -0.67945 0.3048)
			(stroke
				(width 0.1)
				(type default)
			)
			(layer "B.Fab")
		)
		(fp_line
			(start -0.67945 0.3048)
			(end -0.120396 0.3048)
			(stroke
				(width 0.1)
				(type default)
			)
			(layer "B.Fab")
		)
		(fp_line
			(start -0.12065 -0.3048)
			(end -0.67945 -0.3048)
			(stroke
				(width 0.1)
				(type default)
			)
			(layer "B.Fab")
		)
		(fp_line
			(start -0.12065 -0.2794)
			(end -0.12065 -0.3048)
			(stroke
				(width 0.1)
				(type default)
			)
			(layer "B.Fab")
		)
		(fp_line
			(start -0.120396 0.2794)
			(end 0.12065 0.2794)
			(stroke
				(width 0.1)
				(type default)
			)
			(layer "B.Fab")
		)
		(fp_line
			(start -0.120396 0.3048)
			(end -0.120396 0.2794)
			(stroke
				(width 0.1)
				(type default)
			)
			(layer "B.Fab")
		)
		(fp_line
			(start 0.12065 -0.305054)
			(end 0.12065 -0.2794)
			(stroke
				(width 0.1)
				(type default)
			)
			(layer "B.Fab")
		)
		(fp_line
			(start 0.12065 -0.2794)
			(end -0.12065 -0.2794)
			(stroke
				(width 0.1)
				(type default)
			)
			(layer "B.Fab")
		)
		(fp_line
			(start 0.12065 0.2794)
			(end 0.12065 0.3048)
			(stroke
				(width 0.1)
				(type default)
			)
			(layer "B.Fab")
		)
		(fp_line
			(start 0.12065 0.3048)
			(end 0.67945 0.3048)
			(stroke
				(width 0.1)
				(type default)
			)
			(layer "B.Fab")
		)
		(fp_line
			(start 0.67945 -0.305054)
			(end 0.12065 -0.305054)
			(stroke
				(width 0.1)
				(type default)
			)
			(layer "B.Fab")
		)
		(fp_line
			(start 0.67945 0.3048)
			(end 0.67945 -0.305054)
			(stroke
				(width 0.1)
				(type default)
			)
			(layer "B.Fab")
		)
		(pad "1" smd circle
			(at 0.40005 0 180)
			(size 0 0)
			(layers "B.Cu" "B.Mask" "B.Paste")
			(net "PVDDCR_SOC_P1")
		)
		(pad "2" smd circle
			(at -0.40005 0 180)
			(size 0 0)
			(layers "B.Cu" "B.Mask" "B.Paste")
			(net "GND")
		)
	)
)
